# T6G (Grand Teton) — schematic netlist excerpt (pin names and nets, part order shuffled) for the footprints in the layout excerpt that follows; sources: Cadence DE-HDL packaged netlist, KiCad conversion of 04192023_DAF0TMB3IC0_F0TG_MB_C_brd_V02_OCP.brd

R6037  Q_RES  2K 1% EMPTY  pkg 0402LF  page 151 : A = SMB_1_PLD_3V3AUX_SDA ; B = P3V3_AUX
R432  Q_RES  10M 1% CHIP  pkg 0402LF  page 28 : A = XTAL_CPU0_X48M_X1 ; B = XTAL_CPU0_X48M_X2_R

(kicad_pcb
	(version 20260206)
	(generator "pcbnew")
	(generator_version "10.0")
	(general
		(thickness 1.6)
		(legacy_teardrops no)
	)
	(paper "A4")
	(title_block
		(title "04192023_DAF0TMB3IC0_F0TG_MB_C_brd_V02_OCP.brd")
		(comment 1 "Grand Teton / footprints 5960-5961 of 8354")
	)
	(layers
		(0 "F.Cu" signal "TOP")
		(4 "In1.Cu" signal "GND")
		(6 "In2.Cu" signal "IN1")
		(8 "In3.Cu" signal "GND1")
		(10 "In4.Cu" signal "IN2")
		(12 "In5.Cu" signal "GND2")
		(14 "In6.Cu" signal "IN3")
		(16 "In7.Cu" signal "GND3")
		(18 "In8.Cu" signal "VCC")
		(20 "In9.Cu" signal "VCC1")
		(22 "In10.Cu" signal "GND4")
		(24 "In11.Cu" signal "IN4")
		(26 "In12.Cu" signal "GND5")
		(28 "In13.Cu" signal "IN5")
		(30 "In14.Cu" signal "GND6")
		(32 "In15.Cu" signal "IN6")
		(34 "In16.Cu" signal "GND7")
		(2 "B.Cu" signal "BOTTOM")
		(9 "F.Adhes" user "F.Adhesive")
		(11 "B.Adhes" user "B.Adhesive")
		(13 "F.Paste" user "Package Geometry/Pastemask Top")
		(15 "B.Paste" user "Package Geometry/Pastemask Bottom")
		(5 "F.SilkS" user "Ref Des/Silkscreen Top")
		(7 "B.SilkS" user "Ref Des/Silkscreen Bottom")
		(1 "F.Mask" user "Board Geometry/Soldermask Top")
		(3 "B.Mask" user "Board Geometry/Soldermask Bottom")
		(17 "Dwgs.User" user "User.Drawings")
		(19 "Cmts.User" user "User.Comments")
		(21 "Eco1.User" user "User.Eco1")
		(23 "Eco2.User" user "User.Eco2")
		(25 "Edge.Cuts" user "Board Geometry/Outline")
		(27 "Margin" user)
		(31 "F.CrtYd" user "Package Geometry/Place Bound Top")
		(29 "B.CrtYd" user "Package Geometry/Place Bound Bottom")
		(35 "F.Fab" user "Ref Des/Assembly Top")
		(33 "B.Fab" user "Ref Des/Assembly Bottom")
	)
	(footprint ""
		(layer "B.Cu")
		(at 396.157958 -313.477148 180)
		(property "Reference" "R432"
			(at 0 0 0)
			(layer "B.SilkS")
			(hide yes)
			(effects
				(font
					(size 1.27 1.27)
				)
				(justify mirror)
			)
		)
		(property "Value" ""
			(at 0 0 0)
			(layer "B.Fab")
			(effects
				(font
					(size 1.27 1.27)
				)
				(justify mirror)
			)
		)
		(duplicate_pad_numbers_are_jumpers no)
		(fp_line
			(start 0.7874 0.4064)
			(end 0.7874 -0.4064)
			(stroke
				(width 0.1524)
				(type default)
			)
			(layer "B.SilkS")
		)
		(fp_line
			(start 0.7874 -0.4064)
			(end -0.7874 -0.4064)
			(stroke
				(width 0.1524)
				(type default)
			)
			(layer "B.SilkS")
		)
		(fp_line
			(start -0.7874 0.4064)
			(end 0.7874 0.4064)
			(stroke
				(width 0.1524)
				(type default)
			)
			(layer "B.SilkS")
		)
		(fp_line
			(start -0.7874 -0.4064)
			(end -0.7874 0.4064)
			(stroke
				(width 0.1524)
				(type default)
			)
			(layer "B.SilkS")
		)
		(fp_line
			(start 0.67945 0.3048)
			(end 0.67945 -0.305054)
			(stroke
				(width 0.1)
				(type default)
			)
			(layer "B.Fab")
		)
		(fp_line
			(start 0.67945 -0.305054)
			(end 0.12065 -0.305054)
			(stroke
				(width 0.1)
				(type default)
			)
			(layer "B.Fab")
		)
		(fp_line
			(start 0.12065 0.3048)
			(end 0.67945 0.3048)
			(stroke
				(width 0.1)
				(type default)
			)
			(layer "B.Fab")
		)
		(fp_line
			(start 0.12065 0.2794)
			(end 0.12065 0.3048)
			(stroke
				(width 0.1)
				(type default)
			)
			(layer "B.Fab")
		)
		(fp_line
			(start 0.12065 -0.2794)
			(end -0.12065 -0.2794)
			(stroke
				(width 0.1)
				(type default)
			)
			(layer "B.Fab")
		)
		(fp_line
			(start 0.12065 -0.305054)
			(end 0.12065 -0.2794)
			(stroke
				(width 0.1)
				(type default)
			)
			(layer "B.Fab")
		)
		(fp_line
			(start -0.120396 0.3048)
			(end -0.120396 0.2794)
			(stroke
				(width 0.1)
				(type default)
			)
			(layer "B.Fab")
		)
		(fp_line
			(start -0.120396 0.2794)
			(end 0.12065 0.2794)
			(stroke
				(width 0.1)
				(type default)
			)
			(layer "B.Fab")
		)
		(fp_line
			(start -0.12065 -0.2794)
			(end -0.12065 -0.3048)
			(stroke
				(width 0.1)
				(type default)
			)
			(layer "B.Fab")
		)
		(fp_line
			(start -0.12065 -0.3048)
			(end -0.67945 -0.3048)
			(stroke
				(width 0.1)
				(type default)
			)
			(layer "B.Fab")
		)
		(fp_line
			(start -0.67945 0.3048)
			(end -0.120396 0.3048)
			(stroke
				(width 0.1)
				(type default)
			)
			(layer "B.Fab")
		)
		(fp_line
			(start -0.67945 -0.3048)
			(end -0.67945 0.3048)
			(stroke
				(width 0.1)
				(type default)
			)
			(layer "B.Fab")
		)
		(pad "1" smd circle
			(at 0.40005 0)
			(size 0 0)
			(layers "B.Cu" "B.Mask" "B.Paste")
			(net "XTAL_CPU0_X48M_X1")
		)
		(pad "2" smd circle
			(at -0.40005 0)
			(size 0 0)
			(layers "B.Cu" "B.Mask" "B.Paste")
			(net "XTAL_CPU0_X48M_X2_R")
		)
	)
	(footprint ""
		(layer "B.Cu")
		(at 159.383984 -20.056094 90)
		(property "Reference" "R6037"
			(at 0 0 90)
			(layer "B.SilkS")
			(hide yes)
			(effects
				(font
					(size 1.27 1.27)
				)
				(justify mirror)
			)
		)
		(property "Value" ""
			(at 0 0 90)
			(layer "B.Fab")
			(effects
				(font
					(size 1.27 1.27)
				)
				(justify mirror)
			)
		)
		(duplicate_pad_numbers_are_jumpers no)
		(fp_line
			(start 0.7874 -0.4064)
			(end -0.7874 -0.4064)
			(stroke
				(width 0.1524)
				(type default)
			)
			(layer "B.SilkS")
		)
		(fp_line
			(start -0.7874 -0.4064)
			(end -0.7874 0.4064)
			(stroke
				(width 0.1524)
				(type default)
			)
			(layer "B.SilkS")
		)
		(fp_line
			(start 0.7874 0.4064)
			(end 0.7874 -0.4064)
			(stroke
				(width 0.1524)
				(type default)
			)
			(layer "B.SilkS")
		)
		(fp_line
			(start -0.7874 0.4064)
			(end 0.7874 0.4064)
			(stroke
				(width 0.1524)
				(type default)
			)
			(layer "B.SilkS")
		)
		(fp_line
			(start 0.67945 -0.305054)
			(end 0.12065 -0.305054)
			(stroke
				(width 0.1)
				(type default)
			)
			(layer "B.Fab")
		)
		(fp_line
			(start 0.12065 -0.305054)
			(end 0.12065 -0.2794)
			(stroke
				(width 0.1)
				(type default)
			)
			(layer "B.Fab")
		)
		(fp_line
			(start -0.12065 -0.3048)
			(end -0.67945 -0.3048)
			(stroke
				(width 0.1)
				(type default)
			)
			(layer "B.Fab")
		)
		(fp_line
			(start -0.67945 -0.3048)
			(end -0.67945 0.3048)
			(stroke
				(width 0.1)
				(type default)
			)
			(layer "B.Fab")
		)
		(fp_line
			(start 0.12065 -0.2794)
			(end -0.12065 -0.2794)
			(stroke
				(width 0.1)
				(type default)
			)
			(layer "B.Fab")
		)
		(fp_line
			(start -0.12065 -0.2794)
			(end -0.12065 -0.3048)
			(stroke
				(width 0.1)
				(type default)
			)
			(layer "B.Fab")
		)
		(fp_line
			(start 0.12065 0.2794)
			(end 0.12065 0.3048)
			(stroke
				(width 0.1)
				(type default)
			)
			(layer "B.Fab")
		)
		(fp_line
			(start -0.120396 0.2794)
			(end 0.12065 0.2794)
			(stroke
				(width 0.1)
				(type default)
			)
			(layer "B.Fab")
		)
		(fp_line
			(start 0.67945 0.3048)
			(end 0.67945 -0.305054)
			(stroke
				(width 0.1)
				(type default)
			)
			(layer "B.Fab")
		)
		(fp_line
			(start 0.12065 0.3048)
			(end 0.67945 0.3048)
			(stroke
				(width 0.1)
				(type default)
			)
			(layer "B.Fab")
		)
		(fp_line
			(start -0.120396 0.3048)
			(end -0.120396 0.2794)
			(stroke
				(width 0.1)
				(type default)
			)
			(layer "B.Fab")
		)
		(fp_line
			(start -0.67945 0.3048)
			(end -0.120396 0.3048)
			(stroke
				(width 0.1)
				(type default)
			)
			(layer "B.Fab")
		)
		(pad "1" smd circle
			(at 0.40005 0 270)
			(size 0 0)
			(layers "B.Cu" "B.Mask" "B.Paste")
			(net "SMB_1_PLD_3V3AUX_SDA")
		)
		(pad "2" smd circle
			(at -0.40005 0 270)
			(size 0 0)
			(layers "B.Cu" "B.Mask" "B.Paste")
			(net "P3V3_AUX")
		)
	)
)
